(kicad_pcb
	(version 20241229)
	(generator "pcbnew")
	(generator_version "9.0")
	(general
		(thickness 1.61)
		(legacy_teardrops no)
	)
	(paper "A3")
	(title_block
		(title "SO-DIMM DDR5 Tester")
		(date "2025-11-26")
		(rev "1.3.0")
		(comment 9 "footprints 486-491 of 627")
	)
	(layers
		(0 "F.Cu" signal)
		(4 "In1.Cu" power)
		(6 "In2.Cu" mixed)
		(8 "In3.Cu" power)
		(10 "In4.Cu" mixed)
		(12 "In5.Cu" power)
		(14 "In6.Cu" mixed)
		(16 "In7.Cu" power)
		(18 "In8.Cu" power)
		(20 "In9.Cu" mixed)
		(22 "In10.Cu" power)
		(2 "B.Cu" signal)
		(9 "F.Adhes" user "F.Adhesive")
		(11 "B.Adhes" user "B.Adhesive")
		(13 "F.Paste" user)
		(15 "B.Paste" user)
		(5 "F.SilkS" user "F.Silkscreen")
		(7 "B.SilkS" user "B.Silkscreen")
		(1 "F.Mask" user)
		(3 "B.Mask" user)
		(17 "Dwgs.User" user "User.Drawings")
		(19 "Cmts.User" user "User.Comments")
		(21 "Eco1.User" user "User.Eco1")
		(23 "Eco2.User" user "User.Eco2")
		(25 "Edge.Cuts" user)
		(27 "Margin" user)
		(31 "F.CrtYd" user "F.Courtyard")
		(29 "B.CrtYd" user "B.Courtyard")
		(35 "F.Fab" user)
		(33 "B.Fab" user)
	)
	(footprint "antmicro-footprints:TP_SMD_1mm"
		(layer "B.Cu")
		(at 97.5 188.275 180)
		(property "Reference" "TP43"
			(at -3.3 -0.425 0)
			(layer "B.SilkS")
			(effects
				(font
					(size 0.7 0.7)
					(thickness 0.15)
				)
				(justify left bottom mirror)
			)
		)
		(property "Value" "TP_1mm_SMD"
			(at 0 -1.4 0)
			(layer "B.Fab")
			(effects
				(font
					(size 0.7 0.7)
					(thickness 0.15)
				)
				(justify left bottom mirror)
			)
		)
		(property "MPN" ""
			(at 0 0 0)
			(unlocked yes)
			(layer "B.Fab")
			(hide yes)
			(effects
				(font
					(size 1 1)
					(thickness 0.15)
				)
				(justify mirror)
			)
		)
		(property "Manufacturer" ""
			(at 0 0 0)
			(unlocked yes)
			(layer "B.Fab")
			(hide yes)
			(effects
				(font
					(size 1 1)
					(thickness 0.15)
				)
				(justify mirror)
			)
		)
		(property "Author" "Antmicro"
			(at 0 0 0)
			(unlocked yes)
			(layer "B.Fab")
			(hide yes)
			(effects
				(font
					(size 1 1)
					(thickness 0.15)
				)
				(justify mirror)
			)
		)
		(property "License" "Apache-2.0"
			(at 0 0 0)
			(unlocked yes)
			(layer "B.Fab")
			(hide yes)
			(effects
				(font
					(size 1 1)
					(thickness 0.15)
				)
				(justify mirror)
			)
		)
		(sheetname "/Debug FTDI/")
		(sheetfile "debug-ftdi.kicad_sch")
		(attr exclude_from_pos_files)
		(fp_circle
			(center 0 0)
			(end 0.6 0)
			(stroke
				(width 0.05)
				(type default)
			)
			(fill no)
			(layer "B.CrtYd")
		)
		(fp_text user "${REFERENCE}"
			(at -0.5 -2.8 0)
			(layer "B.Fab")
			(effects
				(font
					(size 0.7 0.7)
					(thickness 0.15)
				)
				(justify left bottom mirror)
			)
		)
		(fp_text user "License: Apache-2.0"
			(at -0.5 -5.2 0)
			(layer "B.Fab")
			(effects
				(font
					(size 0.7 0.7)
					(thickness 0.15)
				)
				(justify left bottom mirror)
			)
		)
		(fp_text user "Author: Antmicro"
			(at -0.5 -4 0)
			(layer "B.Fab")
			(effects
				(font
					(size 0.7 0.7)
					(thickness 0.15)
				)
				(justify left bottom mirror)
			)
		)
		(pad "1" smd circle
			(at 0 0 180)
			(size 1 1)
			(layers "B.Cu" "B.Mask")
			(net 46 "/Debug FTDI/JTAG.TCK")
			(pinfunction "1")
			(pintype "passive")
		)
	)
	(footprint "antmicro-footprints:R_0402_1005Metric"
		(layer "B.Cu")
		(at 114.800501 181.249999)
		(descr "Resistor SMD 0402")
		(tags "resistor SMD 0402")
		(property "Reference" "R10"
			(at 1.099499 -0.649999 180)
			(layer "B.SilkS")
			(effects
				(font
					(size 0.7 0.7)
					(thickness 0.15)
				)
				(justify left bottom mirror)
			)
		)
		(property "Value" "R_100R_0402"
			(at -1.011843 -1.772047 180)
			(layer "B.Fab")
			(effects
				(font
					(size 0.7 0.7)
					(thickness 0.15)
				)
				(justify left bottom mirror)
			)
		)
		(property "Datasheet" "https://www.bourns.com/docs/product-datasheets/cr.pdf"
			(at 0 0 0)
			(layer "F.Fab")
			(hide yes)
			(effects
				(font
					(size 1.27 1.27)
					(thickness 0.15)
				)
			)
		)
		(property "Author" "Antmicro"
			(at 0 0 0)
			(layer "B.Fab")
			(hide yes)
			(effects
				(font
					(size 1 1)
					(thickness 0.15)
				)
				(justify mirror)
			)
		)
		(property "License" "Apache-2.0"
			(at 0 0 0)
			(layer "B.Fab")
			(hide yes)
			(effects
				(font
					(size 1 1)
					(thickness 0.15)
				)
				(justify mirror)
			)
		)
		(property "MPN" "CR0402-FX-1000GLF"
			(at 0 0 0)
			(layer "B.Fab")
			(hide yes)
			(effects
				(font
					(size 1 1)
					(thickness 0.15)
				)
				(justify mirror)
			)
		)
		(property "Manufacturer" "Bourns"
			(at 0 0 0)
			(layer "B.Fab")
			(hide yes)
			(effects
				(font
					(size 1 1)
					(thickness 0.15)
				)
				(justify mirror)
			)
		)
		(property "Tolerance" "1%"
			(at 0 0 0)
			(layer "B.Fab")
			(hide yes)
			(effects
				(font
					(size 1 1)
					(thickness 0.15)
				)
				(justify mirror)
			)
		)
		(property "Val" "100R"
			(at 0 0 0)
			(layer "B.Fab")
			(hide yes)
			(effects
				(font
					(size 1 1)
					(thickness 0.15)
				)
				(justify mirror)
			)
		)
		(sheetname "/HyperRAM + QSPI Flash/")
		(sheetfile "hyperram-flash.kicad_sch")
		(attr exclude_from_pos_files exclude_from_bom dnp)
		(fp_rect
			(start -0.93 0.47)
			(end 0.93 -0.47)
			(stroke
				(width 0.05)
				(type solid)
			)
			(fill no)
			(layer "B.CrtYd")
		)
		(fp_rect
			(start -0.5 0.25)
			(end 0.5 -0.25)
			(stroke
				(width 0.15)
				(type solid)
			)
			(fill no)
			(layer "B.Fab")
		)
		(pad "1" smd roundrect
			(at -0.485 0)
			(size 0.59 0.64)
			(layers "B.Cu" "B.Mask" "B.Paste")
			(roundrect_rratio 0.25)
			(net 630 "/FPGA Config/FLASH.SCK")
			(pintype "passive")
		)
		(pad "2" smd roundrect
			(at 0.485 0)
			(size 0.59 0.64)
			(layers "B.Cu" "B.Mask" "B.Paste")
			(roundrect_rratio 0.25)
			(net 1 "GND")
			(pintype "passive")
		)
	)
	(footprint "antmicro-footprints:C_0402_1005Metric"
		(layer "B.Cu")
		(at 129.55 204.775 90)
		(descr "Capacitor SMD 0402")
		(tags "capacitor SMD 0402")
		(property "Reference" "C223"
			(at 0 0.699 270)
			(layer "B.SilkS")
			(hide yes)
			(effects
				(font
					(size 0.7 0.7)
					(thickness 0.15)
				)
				(justify left bottom mirror)
			)
		)
		(property "Value" "C_100n_0402"
			(at -1.022927 -2.155213 270)
			(layer "B.Fab")
			(effects
				(font
					(size 0.7 0.7)
					(thickness 0.15)
				)
				(justify left bottom mirror)
			)
		)
		(property "Datasheet" "https://www.murata.com/products/productdetail?partno=GRM155R61H104KE14%23"
			(at 0 0 90)
			(layer "F.Fab")
			(hide yes)
			(effects
				(font
					(size 1.27 1.27)
					(thickness 0.15)
				)
			)
		)
		(property "Author" "Antmicro"
			(at 334.325 75.225 0)
			(layer "B.Fab")
			(hide yes)
			(effects
				(font
					(size 1 1)
					(thickness 0.15)
				)
				(justify mirror)
			)
		)
		(property "Dielectric" "X5R"
			(at 334.325 75.225 0)
			(layer "B.Fab")
			(hide yes)
			(effects
				(font
					(size 1 1)
					(thickness 0.15)
				)
				(justify mirror)
			)
		)
		(property "License" "Apache-2.0"
			(at 334.325 75.225 0)
			(layer "B.Fab")
			(hide yes)
			(effects
				(font
					(size 1 1)
					(thickness 0.15)
				)
				(justify mirror)
			)
		)
		(property "MPN" "GRM155R61H104KE14D"
			(at 334.325 75.225 0)
			(layer "B.Fab")
			(hide yes)
			(effects
				(font
					(size 1 1)
					(thickness 0.15)
				)
				(justify mirror)
			)
		)
		(property "Manufacturer" "Murata"
			(at 334.325 75.225 0)
			(layer "B.Fab")
			(hide yes)
			(effects
				(font
					(size 1 1)
					(thickness 0.15)
				)
				(justify mirror)
			)
		)
		(property "Val" "100n"
			(at 334.325 75.225 0)
			(layer "B.Fab")
			(hide yes)
			(effects
				(font
					(size 1 1)
					(thickness 0.15)
				)
				(justify mirror)
			)
		)
		(property "Voltage" "50V"
			(at 334.325 75.225 0)
			(layer "B.Fab")
			(hide yes)
			(effects
				(font
					(size 1 1)
					(thickness 0.15)
				)
				(justify mirror)
			)
		)
		(sheetname "/FPGA MGT Interface/")
		(sheetfile "fpga-mgt.kicad_sch")
		(attr smd)
		(fp_rect
			(start -0.9659 0.481258)
			(end 0.9649 -0.458742)
			(stroke
				(width 0.05)
				(type solid)
			)
			(fill no)
			(layer "B.CrtYd")
		)
		(fp_line
			(start 0.499 -0.248)
			(end -0.499 -0.248)
			(stroke
				(width 0.15)
				(type solid)
			)
			(layer "B.Fab")
		)
		(fp_line
			(start -0.499 -0.248)
			(end -0.499 0.25)
			(stroke
				(width 0.15)
				(type solid)
			)
			(layer "B.Fab")
		)
		(fp_line
			(start 0.499 0.25)
			(end 0.499 -0.248)
			(stroke
				(width 0.15)
				(type solid)
			)
			(layer "B.Fab")
		)
		(fp_line
			(start -0.499 0.25)
			(end 0.499 0.25)
			(stroke
				(width 0.15)
				(type solid)
			)
			(layer "B.Fab")
		)
		(pad "1" smd roundrect
			(at -0.484 0 90)
			(size 0.59 0.64)
			(layers "B.Cu" "B.Mask" "B.Paste")
			(roundrect_rratio 0.25)
			(net 14 "/FPGA MGT Interface/PCIE.CLK_N")
			(pintype "passive")
		)
		(pad "2" smd roundrect
			(at 0.484 0 90)
			(size 0.59 0.64)
			(layers "B.Cu" "B.Mask" "B.Paste")
			(roundrect_rratio 0.25)
			(net 15 "/FPGA MGT Interface/GTR_REFCLK0_N")
			(pintype "passive")
		)
	)
	(footprint "antmicro-footprints:R_0402_1005Metric"
		(layer "B.Cu")
		(at 125 202.85)
		(descr "Resistor SMD 0402")
		(tags "resistor SMD 0402")
		(property "Reference" "R191"
			(at -1.1 0.4 180)
			(layer "B.SilkS")
			(effects
				(font
					(size 0.7 0.7)
					(thickness 0.15)
				)
				(justify left bottom mirror)
			)
		)
		(property "Value" "R_10k_0402"
			(at -1.011843 -1.772047 180)
			(layer "B.Fab")
			(effects
				(font
					(size 0.7 0.7)
					(thickness 0.15)
				)
				(justify left bottom mirror)
			)
		)
		(property "Datasheet" "https://www.bourns.com/docs/product-datasheets/cr.pdf"
			(at 0 0 0)
			(layer "F.Fab")
			(hide yes)
			(effects
				(font
					(size 1.27 1.27)
					(thickness 0.15)
				)
			)
		)
		(property "Author" "Antmicro"
			(at 0 0 0)
			(layer "B.Fab")
			(hide yes)
			(effects
				(font
					(size 1 1)
					(thickness 0.15)
				)
				(justify mirror)
			)
		)
		(property "License" "Apache-2.0"
			(at 0 0 0)
			(layer "B.Fab")
			(hide yes)
			(effects
				(font
					(size 1 1)
					(thickness 0.15)
				)
				(justify mirror)
			)
		)
		(property "MPN" "CR0402-FX-1002GLF"
			(at 0 0 0)
			(layer "B.Fab")
			(hide yes)
			(effects
				(font
					(size 1 1)
					(thickness 0.15)
				)
				(justify mirror)
			)
		)
		(property "Manufacturer" "Bourns"
			(at 0 0 0)
			(layer "B.Fab")
			(hide yes)
			(effects
				(font
					(size 1 1)
					(thickness 0.15)
				)
				(justify mirror)
			)
		)
		(property "Tolerance" "1%"
			(at 0 0 0)
			(layer "B.Fab")
			(hide yes)
			(effects
				(font
					(size 1 1)
					(thickness 0.15)
				)
				(justify mirror)
			)
		)
		(property "Val" "10k"
			(at 0 0 0)
			(layer "B.Fab")
			(hide yes)
			(effects
				(font
					(size 1 1)
					(thickness 0.15)
				)
				(justify mirror)
			)
		)
		(sheetname "/PCIe connector/")
		(sheetfile "pcie-connector.kicad_sch")
		(attr exclude_from_pos_files exclude_from_bom dnp)
		(fp_rect
			(start -0.93 0.47)
			(end 0.93 -0.47)
			(stroke
				(width 0.05)
				(type solid)
			)
			(fill no)
			(layer "B.CrtYd")
		)
		(fp_rect
			(start -0.5 0.25)
			(end 0.5 -0.25)
			(stroke
				(width 0.15)
				(type solid)
			)
			(fill no)
			(layer "B.Fab")
		)
		(pad "1" smd roundrect
			(at -0.485 0)
			(size 0.59 0.64)
			(layers "B.Cu" "B.Mask" "B.Paste")
			(roundrect_rratio 0.25)
			(net 135 "PCIE.PWRGD")
			(pintype "passive")
		)
		(pad "2" smd roundrect
			(at 0.485 0)
			(size 0.59 0.64)
			(layers "B.Cu" "B.Mask" "B.Paste")
			(roundrect_rratio 0.25)
			(net 200 "+3V3")
			(pintype "passive")
		)
	)
	(footprint "antmicro-footprints:R_0402_1005Metric"
		(layer "B.Cu")
		(at 135.75 142.4 -90)
		(descr "Resistor SMD 0402")
		(tags "resistor SMD 0402")
		(property "Reference" "R27"
			(at -3.044968 -0.354606 90)
			(layer "B.SilkS")
			(effects
				(font
					(size 0.7 0.7)
					(thickness 0.15)
				)
				(justify left bottom mirror)
			)
		)
		(property "Value" "R_0R_0402"
			(at -1.011843 -1.772047 90)
			(layer "B.Fab")
			(effects
				(font
					(size 0.7 0.7)
					(thickness 0.15)
				)
				(justify left bottom mirror)
			)
		)
		(property "Datasheet" "https://industrial.panasonic.com/cdbs/www-data/pdf/RDA0000/AOA0000C301.pdf"
			(at 0 0 270)
			(layer "F.Fab")
			(hide yes)
			(effects
				(font
					(size 1.27 1.27)
					(thickness 0.15)
				)
			)
		)
		(property "Author" "Antmicro"
			(at -6.65 278.15 0)
			(layer "B.Fab")
			(hide yes)
			(effects
				(font
					(size 1 1)
					(thickness 0.15)
				)
				(justify mirror)
			)
		)
		(property "Current" "1A"
			(at -6.65 278.15 0)
			(layer "B.Fab")
			(hide yes)
			(effects
				(font
					(size 1 1)
					(thickness 0.15)
				)
				(justify mirror)
			)
		)
		(property "License" "Apache-2.0"
			(at -6.65 278.15 0)
			(layer "B.Fab")
			(hide yes)
			(effects
				(font
					(size 1 1)
					(thickness 0.15)
				)
				(justify mirror)
			)
		)
		(property "MPN" "ERJ2GE0R00X"
			(at -6.65 278.15 0)
			(layer "B.Fab")
			(hide yes)
			(effects
				(font
					(size 1 1)
					(thickness 0.15)
				)
				(justify mirror)
			)
		)
		(property "Manufacturer" "Panasonic"
			(at -6.65 278.15 0)
			(layer "B.Fab")
			(hide yes)
			(effects
				(font
					(size 1 1)
					(thickness 0.15)
				)
				(justify mirror)
			)
		)
		(property "Tolerance" ""
			(at -6.65 278.15 0)
			(layer "B.Fab")
			(hide yes)
			(effects
				(font
					(size 1 1)
					(thickness 0.15)
				)
				(justify mirror)
			)
		)
		(property "Val" "0R"
			(at -6.65 278.15 0)
			(layer "B.Fab")
			(hide yes)
			(effects
				(font
					(size 1 1)
					(thickness 0.15)
				)
				(justify mirror)
			)
		)
		(sheetname "/DDR5 SODIMM/")
		(sheetfile "ddr5-sodimm.kicad_sch")
		(attr smd)
		(fp_rect
			(start -0.93 0.47)
			(end 0.93 -0.47)
			(stroke
				(width 0.05)
				(type solid)
			)
			(fill no)
			(layer "B.CrtYd")
		)
		(fp_rect
			(start -0.5 0.25)
			(end 0.5 -0.25)
			(stroke
				(width 0.15)
				(type solid)
			)
			(fill no)
			(layer "B.Fab")
		)
		(pad "1" smd roundrect
			(at -0.485 0 270)
			(size 0.59 0.64)
			(layers "B.Cu" "B.Mask" "B.Paste")
			(roundrect_rratio 0.25)
			(net 140 "/DDR5 SODIMM/VSS_DET1")
			(pintype "passive")
		)
		(pad "2" smd roundrect
			(at 0.485 0 270)
			(size 0.59 0.64)
			(layers "B.Cu" "B.Mask" "B.Paste")
			(roundrect_rratio 0.25)
			(net 248 "~{DDR_PRESENCE}")
			(pintype "passive")
		)
	)
	(footprint "antmicro-footprints:C_0402_1005Metric"
		(layer "B.Cu")
		(at 129.375501 180.801 -90)
		(descr "Capacitor SMD 0402 (1005 Metric), square (rectangular) end terminal, IPC_7351 nominal, (Body size source: IPC-SM-782 page 76, https://www.pcb-3d.com/wordpress/wp-content/uploads/ipc-sm-782a_amendment_1_and_2.pdf)")
		(tags "capacitor 0402")
		(property "Reference" "C30"
			(at 0 1.17 90)
			(layer "B.SilkS")
			(hide yes)
			(effects
				(font
					(size 0.7 0.7)
					(thickness 0.15)
				)
				(justify left bottom mirror)
			)
		)
		(property "Value" "C_100n_0402"
			(at 0 -1.169 90)
			(layer "B.Fab")
			(effects
				(font
					(size 0.7 0.7)
					(thickness 0.15)
				)
				(justify left bottom mirror)
			)
		)
		(property "Datasheet" "https://www.murata.com/products/productdetail?partno=GRM155R61H104KE14%23"
			(at 0 0 270)
			(layer "F.Fab")
			(hide yes)
			(effects
				(font
					(size 1.27 1.27)
					(thickness 0.15)
				)
			)
		)
		(property "Author" "Antmicro"
			(at -51.425499 310.176501 0)
			(layer "B.Fab")
			(hide yes)
			(effects
				(font
					(size 1 1)
					(thickness 0.15)
				)
				(justify mirror)
			)
		)
		(property "Dielectric" "X5R"
			(at -51.425499 310.176501 0)
			(layer "B.Fab")
			(hide yes)
			(effects
				(font
					(size 1 1)
					(thickness 0.15)
				)
				(justify mirror)
			)
		)
		(property "License" "Apache-2.0"
			(at -51.425499 310.176501 0)
			(layer "B.Fab")
			(hide yes)
			(effects
				(font
					(size 1 1)
					(thickness 0.15)
				)
				(justify mirror)
			)
		)
		(property "MPN" "GRM155R61H104KE14D"
			(at -51.425499 310.176501 0)
			(layer "B.Fab")
			(hide yes)
			(effects
				(font
					(size 1 1)
					(thickness 0.15)
				)
				(justify mirror)
			)
		)
		(property "Manufacturer" "Murata"
			(at -51.425499 310.176501 0)
			(layer "B.Fab")
			(hide yes)
			(effects
				(font
					(size 1 1)
					(thickness 0.15)
				)
				(justify mirror)
			)
		)
		(property "Val" "100n"
			(at -51.425499 310.176501 0)
			(layer "B.Fab")
			(hide yes)
			(effects
				(font
					(size 1 1)
					(thickness 0.15)
				)
				(justify mirror)
			)
		)
		(property "Voltage" "50V"
			(at -51.425499 310.176501 0)
			(layer "B.Fab")
			(hide yes)
			(effects
				(font
					(size 1 1)
					(thickness 0.15)
				)
				(justify mirror)
			)
		)
		(sheetname "/FPGA power/")
		(sheetfile "fpga-power.kicad_sch")
		(attr smd)
		(fp_rect
			(start -0.9656 0.4572)
			(end 0.9652 -0.4828)
			(stroke
				(width 0.05)
				(type solid)
			)
			(fill no)
			(layer "B.CrtYd")
		)
		(fp_line
			(start -0.5 0.25)
			(end 0.498 0.25)
			(stroke
				(width 0.15)
				(type solid)
			)
			(layer "B.Fab")
		)
		(fp_line
			(start 0.498 0.25)
			(end 0.498 -0.248)
			(stroke
				(width 0.15)
				(type solid)
			)
			(layer "B.Fab")
		)
		(fp_line
			(start -0.5 -0.248)
			(end -0.5 0.25)
			(stroke
				(width 0.15)
				(type solid)
			)
			(layer "B.Fab")
		)
		(fp_line
			(start 0.498 -0.248)
			(end -0.5 -0.248)
			(stroke
				(width 0.15)
				(type solid)
			)
			(layer "B.Fab")
		)
		(pad "1" smd roundrect
			(at -0.5 0 180)
			(size 0.6 0.6)
			(layers "B.Cu" "B.Mask" "B.Paste")
			(roundrect_rratio 0.25)
			(net 1 "GND")
			(pintype "passive")
		)
		(pad "2" smd roundrect
			(at 0.498 0 270)
			(size 0.6 0.6)
			(layers "B.Cu" "B.Mask" "B.Paste")
			(roundrect_rratio 0.25)
			(net 200 "+3V3")
			(pintype "passive")
		)
	)
)
